(kicad_pcb
	(version 20260206)
	(generator "pcbnew")
	(generator_version "10.0")
	(general
		(thickness 1.6)
		(legacy_teardrops no)
	)
	(paper "A4")
	(title_block
		(title "9054_F0T_PDB_BD_GPU_F_V04_1213_1550_OCP.brd")
		(comment 1 "Grand Teton / footprints 594-598 of 608")
	)
	(layers
		(0 "F.Cu" signal "TOP")
		(4 "In1.Cu" signal "GND")
		(6 "In2.Cu" signal "IN1")
		(8 "In3.Cu" signal "GND1")
		(10 "In4.Cu" signal "VCC")
		(12 "In5.Cu" signal "VCC1")
		(14 "In6.Cu" signal "GND2")
		(16 "In7.Cu" signal "IN2")
		(18 "In8.Cu" signal "GND3")
		(2 "B.Cu" signal "BOTTOM")
		(9 "F.Adhes" user "F.Adhesive")
		(11 "B.Adhes" user "B.Adhesive")
		(13 "F.Paste" user "Package Geometry/Pastemask Top")
		(15 "B.Paste" user "Package Geometry/Pastemask Bottom")
		(5 "F.SilkS" user "Ref Des/Silkscreen Top")
		(7 "B.SilkS" user "Ref Des/Silkscreen Bottom")
		(1 "F.Mask" user "Board Geometry/Soldermask Top")
		(3 "B.Mask" user "Board Geometry/Soldermask Bottom")
		(17 "Dwgs.User" user "User.Drawings")
		(19 "Cmts.User" user "User.Comments")
		(21 "Eco1.User" user "User.Eco1")
		(23 "Eco2.User" user "User.Eco2")
		(25 "Edge.Cuts" user "Board Geometry/Outline")
		(27 "Margin" user)
		(31 "F.CrtYd" user "Package Geometry/Place Bound Top")
		(29 "B.CrtYd" user "Package Geometry/Place Bound Bottom")
		(35 "F.Fab" user "Ref Des/Assembly Top")
		(33 "B.Fab" user "Ref Des/Assembly Bottom")
	)
	(footprint ""
		(layer "B.Cu")
		(at 420.37 -40.468042 180)
		(property "Reference" "U39"
			(at 2.4765 -5.074412 0)
			(unlocked yes)
			(layer "B.SilkS")
			(effects
				(font
					(size 0.7874 0.5842)
					(thickness 0.1524)
				)
				(justify left mirror)
			)
		)
		(property "Value" ""
			(at 0 0 0)
			(layer "B.Fab")
			(effects
				(font
					(size 1.27 1.27)
				)
				(justify mirror)
			)
		)
		(duplicate_pad_numbers_are_jumpers no)
		(fp_line
			(start 2.0066 3.9624)
			(end 2.0066 -3.9624)
			(stroke
				(width 0.1524)
				(type default)
			)
			(layer "B.SilkS")
		)
		(fp_line
			(start 2.0066 -3.9624)
			(end 0.5842 -3.9624)
			(stroke
				(width 0.1524)
				(type default)
			)
			(layer "B.SilkS")
		)
		(fp_line
			(start 0.5842 -3.9624)
			(end 0 -3.3782)
			(stroke
				(width 0.1524)
				(type default)
			)
			(layer "B.SilkS")
		)
		(fp_line
			(start 0 -3.3782)
			(end -0.5842 -3.9624)
			(stroke
				(width 0.1524)
				(type default)
			)
			(layer "B.SilkS")
		)
		(fp_line
			(start -0.5842 -3.9624)
			(end -2.0066 -3.9624)
			(stroke
				(width 0.1524)
				(type default)
			)
			(layer "B.SilkS")
		)
		(fp_line
			(start -2.0066 3.9624)
			(end 2.0066 3.9624)
			(stroke
				(width 0.1524)
				(type default)
			)
			(layer "B.SilkS")
		)
		(fp_line
			(start -2.0066 -3.9624)
			(end -2.0066 3.9624)
			(stroke
				(width 0.1524)
				(type default)
			)
			(layer "B.SilkS")
		)
		(fp_poly
			(pts
				(xy 3.8862 -3.570986) (xy 4.6482 -3.189986) (xy 4.6482 -3.951986)
			)
			(stroke
				(width 0)
				(type default)
			)
			(fill yes)
			(layer "B.SilkS")
		)
		(fp_line
			(start 3.724402 3.80365)
			(end 2.2479 3.80365)
			(stroke
				(width 0.1)
				(type default)
			)
			(layer "B.Fab")
		)
		(fp_line
			(start 3.724402 -3.80365)
			(end 3.724402 3.80365)
			(stroke
				(width 0.1)
				(type default)
			)
			(layer "B.Fab")
		)
		(fp_line
			(start 3.7211 -3.34645)
			(end 3.7211 -3.80365)
			(stroke
				(width 0.1)
				(type default)
			)
			(layer "B.Fab")
		)
		(fp_line
			(start 2.2479 3.9624)
			(end -2.2479 3.9624)
			(stroke
				(width 0.1)
				(type default)
			)
			(layer "B.Fab")
		)
		(fp_line
			(start 2.2479 3.80365)
			(end 2.2479 3.9624)
			(stroke
				(width 0.1)
				(type default)
			)
			(layer "B.Fab")
		)
		(fp_line
			(start 2.2479 -3.80365)
			(end 3.724402 -3.80365)
			(stroke
				(width 0.1)
				(type default)
			)
			(layer "B.Fab")
		)
		(fp_line
			(start 2.2479 -3.974846)
			(end 2.2479 -3.80365)
			(stroke
				(width 0.1)
				(type default)
			)
			(layer "B.Fab")
		)
		(fp_line
			(start -2.2479 3.9624)
			(end -2.2479 3.80365)
			(stroke
				(width 0.1)
				(type default)
			)
			(layer "B.Fab")
		)
		(fp_line
			(start -2.2479 3.80365)
			(end -3.7211 3.80365)
			(stroke
				(width 0.1)
				(type default)
			)
			(layer "B.Fab")
		)
		(fp_line
			(start -2.2479 -3.80365)
			(end -2.2479 -3.974846)
			(stroke
				(width 0.1)
				(type default)
			)
			(layer "B.Fab")
		)
		(fp_line
			(start -2.2479 -3.974846)
			(end 2.2479 -3.974846)
			(stroke
				(width 0.1)
				(type default)
			)
			(layer "B.Fab")
		)
		(fp_line
			(start -3.7211 3.80365)
			(end -3.7211 -3.80365)
			(stroke
				(width 0.1)
				(type default)
			)
			(layer "B.Fab")
		)
		(fp_line
			(start -3.7211 -3.80365)
			(end -2.2479 -3.80365)
			(stroke
				(width 0.1)
				(type default)
			)
			(layer "B.Fab")
		)
		(fp_poly
			(pts
				(xy 3.8862 -3.570986) (xy 4.6482 -3.189986) (xy 4.6482 -3.951986)
			)
			(stroke
				(width 0)
				(type default)
			)
			(fill yes)
			(layer "B.Fab")
		)
		(pad "1" smd rect
			(at 2.921 -3.57505 90)
			(size 0.3556 1.4986)
			(layers "B.Cu" "B.Mask" "B.Paste")
			(net "PU_U39_PIN1")
		)
		(pad "2" smd rect
			(at 2.921 -2.925064 90)
			(size 0.3556 1.4986)
			(layers "B.Cu" "B.Mask" "B.Paste")
			(net "PCA9555_2_A1")
		)
		(pad "3" smd rect
			(at 2.921 -2.275078 90)
			(size 0.3556 1.4986)
			(layers "B.Cu" "B.Mask" "B.Paste")
			(net "PCA9555_2_A2")
		)
		(pad "4" smd rect
			(at 2.921 -1.625092 90)
			(size 0.3556 1.4986)
			(layers "B.Cu" "B.Mask" "B.Paste")
			(net "PWRGD_P12V_FAN_LED")
		)
		(pad "5" smd rect
			(at 2.921 -0.975106 90)
			(size 0.3556 1.4986)
			(layers "B.Cu" "B.Mask" "B.Paste")
			(net "FM_HS1_EN_BUSBAR_BUF")
		)
		(pad "6" smd rect
			(at 2.921 -0.32512 90)
			(size 0.3556 1.4986)
			(layers "B.Cu" "B.Mask" "B.Paste")
			(net "FM_HS1_EN_FUSE_BUF")
		)
		(pad "7" smd rect
			(at 2.921 0.32512 90)
			(size 0.3556 1.4986)
			(layers "B.Cu" "B.Mask" "B.Paste")
			(net "FM_HS2_EN_BUSBAR_BUF")
		)
		(pad "8" smd rect
			(at 2.921 0.975106 90)
			(size 0.3556 1.4986)
			(layers "B.Cu" "B.Mask" "B.Paste")
			(net "FM_HS2_EN_FUSE_BUF")
		)
		(pad "9" smd rect
			(at 2.921 1.625092 90)
			(size 0.3556 1.4986)
			(layers "B.Cu" "B.Mask" "B.Paste")
			(net "TP_U39_P05")
		)
		(pad "10" smd rect
			(at 2.921 2.275078 90)
			(size 0.3556 1.4986)
			(layers "B.Cu" "B.Mask" "B.Paste")
			(net "TP_U39_P06")
		)
		(pad "11" smd rect
			(at 2.921 2.925064 90)
			(size 0.3556 1.4986)
			(layers "B.Cu" "B.Mask" "B.Paste")
			(net "TP_U39_P07")
		)
		(pad "12" smd rect
			(at 2.921 3.57505 90)
			(size 0.3556 1.4986)
			(layers "B.Cu" "B.Mask" "B.Paste")
			(net "GND")
		)
		(pad "13" smd rect
			(at -2.921 3.57505 90)
			(size 0.3556 1.4986)
			(layers "B.Cu" "B.Mask" "B.Paste")
			(net "TP_U39_P10")
		)
		(pad "14" smd rect
			(at -2.921 2.925064 90)
			(size 0.3556 1.4986)
			(layers "B.Cu" "B.Mask" "B.Paste")
			(net "TP_U39_P11")
		)
		(pad "15" smd rect
			(at -2.921 2.275078 90)
			(size 0.3556 1.4986)
			(layers "B.Cu" "B.Mask" "B.Paste")
			(net "TP_U39_P12")
		)
		(pad "16" smd rect
			(at -2.921 1.625092 90)
			(size 0.3556 1.4986)
			(layers "B.Cu" "B.Mask" "B.Paste")
			(net "TP_U39_P13")
		)
		(pad "17" smd rect
			(at -2.921 0.975106 90)
			(size 0.3556 1.4986)
			(layers "B.Cu" "B.Mask" "B.Paste")
			(net "TP_U39_P14")
		)
		(pad "18" smd rect
			(at -2.921 0.32512 90)
			(size 0.3556 1.4986)
			(layers "B.Cu" "B.Mask" "B.Paste")
			(net "TP_U39_P15")
		)
		(pad "19" smd rect
			(at -2.921 -0.32512 90)
			(size 0.3556 1.4986)
			(layers "B.Cu" "B.Mask" "B.Paste")
			(net "TP_U39_P16")
		)
		(pad "20" smd rect
			(at -2.921 -0.975106 90)
			(size 0.3556 1.4986)
			(layers "B.Cu" "B.Mask" "B.Paste")
			(net "TP_U39_P17")
		)
		(pad "21" smd rect
			(at -2.921 -1.625092 90)
			(size 0.3556 1.4986)
			(layers "B.Cu" "B.Mask" "B.Paste")
			(net "PCA9555_2_A0")
		)
		(pad "22" smd rect
			(at -2.921 -2.275078 90)
			(size 0.3556 1.4986)
			(layers "B.Cu" "B.Mask" "B.Paste")
			(net "SMB_IOEXP_2_SCL")
		)
		(pad "23" smd rect
			(at -2.921 -2.925064 90)
			(size 0.3556 1.4986)
			(layers "B.Cu" "B.Mask" "B.Paste")
			(net "SMB_IOEXP_2_SDA")
		)
		(pad "24" smd rect
			(at -2.921 -3.57505 90)
			(size 0.3556 1.4986)
			(layers "B.Cu" "B.Mask" "B.Paste")
			(net "P3V3_AUX")
		)
	)
	(footprint ""
		(layer "B.Cu")
		(at 161.336736 -74.93 -90)
		(property "Reference" "PR7008"
			(at 0 0 90)
			(layer "B.SilkS")
			(hide yes)
			(effects
				(font
					(size 1.27 1.27)
				)
				(justify mirror)
			)
		)
		(property "Value" ""
			(at 0 0 90)
			(layer "B.Fab")
			(effects
				(font
					(size 1.27 1.27)
				)
				(justify mirror)
			)
		)
		(duplicate_pad_numbers_are_jumpers no)
		(fp_line
			(start -0.7874 0.4064)
			(end 0.7874 0.4064)
			(stroke
				(width 0.1524)
				(type default)
			)
			(layer "B.SilkS")
		)
		(fp_line
			(start 0.7874 0.4064)
			(end 0.7874 -0.4064)
			(stroke
				(width 0.1524)
				(type default)
			)
			(layer "B.SilkS")
		)
		(fp_line
			(start -0.7874 -0.4064)
			(end -0.7874 0.4064)
			(stroke
				(width 0.1524)
				(type default)
			)
			(layer "B.SilkS")
		)
		(fp_line
			(start 0.7874 -0.4064)
			(end -0.7874 -0.4064)
			(stroke
				(width 0.1524)
				(type default)
			)
			(layer "B.SilkS")
		)
		(fp_line
			(start -0.67945 0.3048)
			(end -0.120396 0.3048)
			(stroke
				(width 0.1)
				(type default)
			)
			(layer "B.Fab")
		)
		(fp_line
			(start -0.120396 0.3048)
			(end -0.120396 0.2794)
			(stroke
				(width 0.1)
				(type default)
			)
			(layer "B.Fab")
		)
		(fp_line
			(start 0.12065 0.3048)
			(end 0.67945 0.3048)
			(stroke
				(width 0.1)
				(type default)
			)
			(layer "B.Fab")
		)
		(fp_line
			(start 0.67945 0.3048)
			(end 0.67945 -0.305054)
			(stroke
				(width 0.1)
				(type default)
			)
			(layer "B.Fab")
		)
		(fp_line
			(start -0.120396 0.2794)
			(end 0.12065 0.2794)
			(stroke
				(width 0.1)
				(type default)
			)
			(layer "B.Fab")
		)
		(fp_line
			(start 0.12065 0.2794)
			(end 0.12065 0.3048)
			(stroke
				(width 0.1)
				(type default)
			)
			(layer "B.Fab")
		)
		(fp_line
			(start -0.12065 -0.2794)
			(end -0.12065 -0.3048)
			(stroke
				(width 0.1)
				(type default)
			)
			(layer "B.Fab")
		)
		(fp_line
			(start 0.12065 -0.2794)
			(end -0.12065 -0.2794)
			(stroke
				(width 0.1)
				(type default)
			)
			(layer "B.Fab")
		)
		(fp_line
			(start -0.67945 -0.3048)
			(end -0.67945 0.3048)
			(stroke
				(width 0.1)
				(type default)
			)
			(layer "B.Fab")
		)
		(fp_line
			(start -0.12065 -0.3048)
			(end -0.67945 -0.3048)
			(stroke
				(width 0.1)
				(type default)
			)
			(layer "B.Fab")
		)
		(fp_line
			(start 0.12065 -0.305054)
			(end 0.12065 -0.2794)
			(stroke
				(width 0.1)
				(type default)
			)
			(layer "B.Fab")
		)
		(fp_line
			(start 0.67945 -0.305054)
			(end 0.12065 -0.305054)
			(stroke
				(width 0.1)
				(type default)
			)
			(layer "B.Fab")
		)
		(pad "1" smd circle
			(at 0.40005 0 90)
			(size 0 0)
			(layers "B.Cu" "B.Mask" "B.Paste")
			(net "P52V_HS2_TMR")
		)
		(pad "2" smd circle
			(at -0.40005 0 90)
			(size 0 0)
			(layers "B.Cu" "B.Mask" "B.Paste")
			(net "HS2_TMR1")
		)
	)
	(footprint ""
		(layer "B.Cu")
		(at 343.535 -37.973 180)
		(property "Reference" "PC585"
			(at 0 0 0)
			(layer "B.SilkS")
			(hide yes)
			(effects
				(font
					(size 1.27 1.27)
				)
				(justify mirror)
			)
		)
		(property "Value" ""
			(at 0 0 0)
			(layer "B.Fab")
			(effects
				(font
					(size 1.27 1.27)
				)
				(justify mirror)
			)
		)
		(duplicate_pad_numbers_are_jumpers no)
		(fp_line
			(start 1.2954 0.5842)
			(end 1.2954 -0.5842)
			(stroke
				(width 0.1524)
				(type default)
			)
			(layer "B.SilkS")
		)
		(fp_line
			(start 1.2954 -0.5842)
			(end -1.2954 -0.5842)
			(stroke
				(width 0.1524)
				(type default)
			)
			(layer "B.SilkS")
		)
		(fp_line
			(start -1.2954 0.5842)
			(end 1.2954 0.5842)
			(stroke
				(width 0.1524)
				(type default)
			)
			(layer "B.SilkS")
		)
		(fp_line
			(start -1.2954 -0.5842)
			(end -1.2954 0.5842)
			(stroke
				(width 0.1524)
				(type default)
			)
			(layer "B.SilkS")
		)
		(fp_line
			(start 1.1938 0.4064)
			(end 1.1938 -0.4064)
			(stroke
				(width 0.1)
				(type default)
			)
			(layer "B.Fab")
		)
		(fp_line
			(start 1.1938 -0.4064)
			(end 0.8636 -0.4064)
			(stroke
				(width 0.1)
				(type default)
			)
			(layer "B.Fab")
		)
		(fp_line
			(start 0.8636 0.4572)
			(end 0.8636 0.4064)
			(stroke
				(width 0.1)
				(type default)
			)
			(layer "B.Fab")
		)
		(fp_line
			(start 0.8636 0.4064)
			(end 1.1938 0.4064)
			(stroke
				(width 0.1)
				(type default)
			)
			(layer "B.Fab")
		)
		(fp_line
			(start 0.8636 -0.4064)
			(end 0.8636 -0.4572)
			(stroke
				(width 0.1)
				(type default)
			)
			(layer "B.Fab")
		)
		(fp_line
			(start 0.8636 -0.4572)
			(end -0.8636 -0.4572)
			(stroke
				(width 0.1)
				(type default)
			)
			(layer "B.Fab")
		)
		(fp_line
			(start -0.8636 0.4572)
			(end 0.8636 0.4572)
			(stroke
				(width 0.1)
				(type default)
			)
			(layer "B.Fab")
		)
		(fp_line
			(start -0.8636 0.4064)
			(end -0.8636 0.4572)
			(stroke
				(width 0.1)
				(type default)
			)
			(layer "B.Fab")
		)
		(fp_line
			(start -0.8636 -0.4064)
			(end -1.1938 -0.4064)
			(stroke
				(width 0.1)
				(type default)
			)
			(layer "B.Fab")
		)
		(fp_line
			(start -0.8636 -0.4572)
			(end -0.8636 -0.4064)
			(stroke
				(width 0.1)
				(type default)
			)
			(layer "B.Fab")
		)
		(fp_line
			(start -1.1938 0.4064)
			(end -0.8636 0.4064)
			(stroke
				(width 0.1)
				(type default)
			)
			(layer "B.Fab")
		)
		(fp_line
			(start -1.1938 -0.4064)
			(end -1.1938 0.4064)
			(stroke
				(width 0.1)
				(type default)
			)
			(layer "B.Fab")
		)
		(pad "1" smd rect
			(at 0.7366 0 90)
			(size 0.7112 0.8128)
			(layers "B.Cu" "B.Mask" "B.Paste")
			(net "P52V_HS1_4287_GATE2_RC")
		)
		(pad "2" smd rect
			(at -0.7366 0 90)
			(size 0.7112 0.8128)
			(layers "B.Cu" "B.Mask" "B.Paste")
			(net "P52V_HS1")
		)
	)
	(footprint ""
		(layer "B.Cu")
		(at 270.4084 -84.201 90)
		(property "Reference" "PR481"
			(at 0 0 90)
			(layer "B.SilkS")
			(hide yes)
			(effects
				(font
					(size 1.27 1.27)
				)
				(justify mirror)
			)
		)
		(property "Value" ""
			(at 0 0 90)
			(layer "B.Fab")
			(effects
				(font
					(size 1.27 1.27)
				)
				(justify mirror)
			)
		)
		(duplicate_pad_numbers_are_jumpers no)
		(fp_line
			(start 1.651 -0.8382)
			(end -1.651 -0.8382)
			(stroke
				(width 0.1524)
				(type default)
			)
			(layer "B.SilkS")
		)
		(fp_line
			(start -1.651 -0.8382)
			(end -1.651 0.8382)
			(stroke
				(width 0.1524)
				(type default)
			)
			(layer "B.SilkS")
		)
		(fp_line
			(start 1.651 0.8382)
			(end 1.651 -0.8382)
			(stroke
				(width 0.1524)
				(type default)
			)
			(layer "B.SilkS")
		)
		(fp_line
			(start -1.651 0.8382)
			(end 1.651 0.8382)
			(stroke
				(width 0.1524)
				(type default)
			)
			(layer "B.SilkS")
		)
		(fp_line
			(start 1.559814 -0.7366)
			(end 1.559814 0.7366)
			(stroke
				(width 0.1)
				(type default)
			)
			(layer "B.Fab")
		)
		(fp_line
			(start 1.524 -0.7366)
			(end 1.559814 -0.7366)
			(stroke
				(width 0.1)
				(type default)
			)
			(layer "B.Fab")
		)
		(fp_line
			(start -1.524 -0.7366)
			(end 1.524 -0.7366)
			(stroke
				(width 0.1)
				(type default)
			)
			(layer "B.Fab")
		)
		(fp_line
			(start -1.560576 -0.7366)
			(end -1.524 -0.7366)
			(stroke
				(width 0.1)
				(type default)
			)
			(layer "B.Fab")
		)
		(fp_line
			(start 1.559814 0.7366)
			(end 1.524 0.7366)
			(stroke
				(width 0.1)
				(type default)
			)
			(layer "B.Fab")
		)
		(fp_line
			(start 1.524 0.7366)
			(end -1.524 0.7366)
			(stroke
				(width 0.1)
				(type default)
			)
			(layer "B.Fab")
		)
		(fp_line
			(start -1.524 0.7366)
			(end -1.560576 0.7366)
			(stroke
				(width 0.1)
				(type default)
			)
			(layer "B.Fab")
		)
		(fp_line
			(start -1.560576 0.7366)
			(end -1.560576 -0.7366)
			(stroke
				(width 0.1)
				(type default)
			)
			(layer "B.Fab")
		)
		(pad "1" smd rect
			(at 0.94996 0 90)
			(size 1.1176 1.3716)
			(layers "B.Cu" "B.Mask" "B.Paste")
			(net "P52V_1")
		)
		(pad "2" smd rect
			(at -0.94996 0 90)
			(size 1.1176 1.3716)
			(layers "B.Cu" "B.Mask" "B.Paste")
			(net "P52V_HS1_UVLO_EN")
		)
	)
	(footprint ""
		(layer "B.Cu")
		(at 262.4074 -69.088 90)
		(property "Reference" "PC588"
			(at 0 0 90)
			(layer "B.SilkS")
			(hide yes)
			(effects
				(font
					(size 1.27 1.27)
				)
				(justify mirror)
			)
		)
		(property "Value" ""
			(at 0 0 90)
			(layer "B.Fab")
			(effects
				(font
					(size 1.27 1.27)
				)
				(justify mirror)
			)
		)
		(duplicate_pad_numbers_are_jumpers no)
		(fp_line
			(start 2.2098 -0.9398)
			(end -2.2098 -0.9398)
			(stroke
				(width 0.1524)
				(type default)
			)
			(layer "B.SilkS")
		)
		(fp_line
			(start -2.2098 -0.9398)
			(end -2.2098 0.9398)
			(stroke
				(width 0.1524)
				(type default)
			)
			(layer "B.SilkS")
		)
		(fp_line
			(start 2.2098 0.9398)
			(end 2.2098 -0.9398)
			(stroke
				(width 0.1524)
				(type default)
			)
			(layer "B.SilkS")
		)
		(fp_line
			(start -2.2098 0.9398)
			(end 2.2098 0.9398)
			(stroke
				(width 0.1524)
				(type default)
			)
			(layer "B.SilkS")
		)
		(fp_line
			(start 1.6764 -0.9398)
			(end -1.6764 -0.9398)
			(stroke
				(width 0.1)
				(type default)
			)
			(layer "B.Fab")
		)
		(fp_line
			(start -1.6764 -0.9398)
			(end -1.6764 -0.889)
			(stroke
				(width 0.1)
				(type default)
			)
			(layer "B.Fab")
		)
		(fp_line
			(start 1.6764 -0.889)
			(end 1.6764 -0.9398)
			(stroke
				(width 0.1)
				(type default)
			)
			(layer "B.Fab")
		)
		(fp_line
			(start -1.6764 -0.889)
			(end -1.6764 -0.8382)
			(stroke
				(width 0.1)
				(type default)
			)
			(layer "B.Fab")
		)
		(fp_line
			(start 2.1082 -0.8382)
			(end 1.6764 -0.8382)
			(stroke
				(width 0.1)
				(type default)
			)
			(layer "B.Fab")
		)
		(fp_line
			(start 1.6764 -0.8382)
			(end 1.6764 -0.889)
			(stroke
				(width 0.1)
				(type default)
			)
			(layer "B.Fab")
		)
		(fp_line
			(start -1.6764 -0.8382)
			(end -2.1082 -0.8382)
			(stroke
				(width 0.1)
				(type default)
			)
			(layer "B.Fab")
		)
		(fp_line
			(start -2.1082 -0.8382)
			(end -2.1082 0.8382)
			(stroke
				(width 0.1)
				(type default)
			)
			(layer "B.Fab")
		)
		(fp_line
			(start 2.1082 0.8382)
			(end 2.1082 -0.8382)
			(stroke
				(width 0.1)
				(type default)
			)
			(layer "B.Fab")
		)
		(fp_line
			(start 1.6764 0.8382)
			(end 2.1082 0.8382)
			(stroke
				(width 0.1)
				(type default)
			)
			(layer "B.Fab")
		)
		(fp_line
			(start -1.6764 0.8382)
			(end -1.6764 0.889)
			(stroke
				(width 0.1)
				(type default)
			)
			(layer "B.Fab")
		)
		(fp_line
			(start -2.1082 0.8382)
			(end -1.6764 0.8382)
			(stroke
				(width 0.1)
				(type default)
			)
			(layer "B.Fab")
		)
		(fp_line
			(start 1.6764 0.889)
			(end 1.6764 0.8382)
			(stroke
				(width 0.1)
				(type default)
			)
			(layer "B.Fab")
		)
		(fp_line
			(start -1.6764 0.889)
			(end -1.6764 0.9398)
			(stroke
				(width 0.1)
				(type default)
			)
			(layer "B.Fab")
		)
		(fp_line
			(start 1.6764 0.9398)
			(end 1.6764 0.889)
			(stroke
				(width 0.1)
				(type default)
			)
			(layer "B.Fab")
		)
		(fp_line
			(start -1.6764 0.9398)
			(end 1.6764 0.9398)
			(stroke
				(width 0.1)
				(type default)
			)
			(layer "B.Fab")
		)
		(pad "1" smd rect
			(at 1.4732 0 90)
			(size 1.1684 1.5748)
			(layers "B.Cu" "B.Mask" "B.Paste")
			(net "P52V_HS1")
		)
		(pad "2" smd rect
			(at -1.4732 0 90)
			(size 1.1684 1.5748)
			(layers "B.Cu" "B.Mask" "B.Paste")
			(net "P52V_HS1_VCP")
		)
	)
)
